# BASEBOARD_FAB2 (Tioga Pass) — schematic netlist excerpt (pin names and nets, part order shuffled) for the footprints in the layout excerpt that follows; sources: Cadence DE-HDL packaged netlist, KiCad conversion of Wiwynn_Tioga_Pass_MB.brd

C1C10  CAP  220PF 50V 10% X7R  pkg 0402LF  page 206 : A = A_TSENSE_PVCCIN_CPU1 ; B = GND
R9A15  RES  1.00K 1% CHIP  pkg 0402  page 111 : A = RST_RSMRST_N ; B = XDP_RSMRST_N
C7G26  CAP  0.22UF 16V 10% X7R  pkg 0402  page 105 : A = P3E_CPU0_PE2_SS_TXN<5> ; B = P3E_CPU0_PE2_SS_C_TXN<5>

(kicad_pcb
	(version 20260206)
	(generator "pcbnew")
	(generator_version "10.0")
	(general
		(thickness 1.6)
		(legacy_teardrops no)
	)
	(paper "A4")
	(title_block
		(title "Wiwynn_Tioga_Pass_MB.brd")
		(comment 1 "Tioga Pass / footprints 1151-1153 of 4770")
	)
	(layers
		(0 "F.Cu" signal "TOP")
		(4 "In1.Cu" signal "L2GND")
		(6 "In2.Cu" signal "L3")
		(8 "In3.Cu" signal "L4GND")
		(10 "In4.Cu" signal "L5")
		(12 "In5.Cu" signal "L6GND")
		(14 "In6.Cu" signal "L7VCC")
		(16 "In7.Cu" signal "L8VCC")
		(18 "In8.Cu" signal "L9GND")
		(20 "In9.Cu" signal "L10")
		(22 "In10.Cu" signal "L11GND")
		(24 "In11.Cu" signal "L12")
		(26 "In12.Cu" signal "L13GND")
		(2 "B.Cu" signal "BOTTOM")
		(9 "F.Adhes" user "F.Adhesive")
		(11 "B.Adhes" user "B.Adhesive")
		(13 "F.Paste" user "Package Geometry/Pastemask Top")
		(15 "B.Paste" user "Package Geometry/Pastemask Bottom")
		(5 "F.SilkS" user "Ref Des/Silkscreen Top")
		(7 "B.SilkS" user "Ref Des/Silkscreen Bottom")
		(1 "F.Mask" user "Board Geometry/Soldermask Top")
		(3 "B.Mask" user "Board Geometry/Soldermask Bottom")
		(17 "Dwgs.User" user "User.Drawings")
		(19 "Cmts.User" user "User.Comments")
		(21 "Eco1.User" user "User.Eco1")
		(23 "Eco2.User" user "User.Eco2")
		(25 "Edge.Cuts" user "Board Geometry/Outline")
		(27 "Margin" user)
		(31 "F.CrtYd" user "Package Geometry/Place Bound Top")
		(29 "B.CrtYd" user "Package Geometry/Place Bound Bottom")
		(35 "F.Fab" user "Ref Des/Assembly Top")
		(33 "B.Fab" user "Ref Des/Assembly Bottom")
	)
	(footprint ""
		(layer "F.Cu")
		(at 398.919192 -10.917936)
		(property "Reference" "C7G26"
			(at 0 0 0)
			(layer "F.SilkS")
			(hide yes)
			(effects
				(font
					(size 1.27 1.27)
				)
			)
		)
		(property "Value" ""
			(at 0 0 0)
			(layer "F.Fab")
			(effects
				(font
					(size 1.27 1.27)
				)
			)
		)
		(duplicate_pad_numbers_are_jumpers no)
		(fp_rect
			(start -0.3048 0.9906)
			(end 0.3048 -0.1016)
			(stroke
				(width 0)
				(type default)
			)
			(fill no)
			(layer "F.CrtYd")
		)
		(fp_line
			(start -0.3048 -0.1016)
			(end -0.3048 0.9906)
			(stroke
				(width 0.1)
				(type default)
			)
			(layer "F.Fab")
		)
		(fp_line
			(start -0.3048 0.9906)
			(end 0.3048 0.9906)
			(stroke
				(width 0.1)
				(type default)
			)
			(layer "F.Fab")
		)
		(fp_line
			(start 0.3048 -0.1016)
			(end -0.3048 -0.1016)
			(stroke
				(width 0.1)
				(type default)
			)
			(layer "F.Fab")
		)
		(fp_line
			(start 0.3048 0.9906)
			(end 0.3048 -0.1016)
			(stroke
				(width 0.1)
				(type default)
			)
			(layer "F.Fab")
		)
		(pad "1" smd rect
			(at 0 0)
			(size 0.508 0.508)
			(layers "F.Cu" "F.Mask" "F.Paste")
			(net "P3E_CPU0_PE2_SS_TXN<5>")
		)
		(pad "2" smd rect
			(at 0 0.889)
			(size 0.508 0.508)
			(layers "F.Cu" "F.Mask" "F.Paste")
			(net "P3E_CPU0_PE2_SS_C_TXN<5>")
		)
		(zone
			(layer "F.Cu")
			(hatch none 0.5)
			(connect_pads
				(clearance 0)
			)
			(min_thickness 0.25)
			(keepout
				(tracks allowed)
				(vias not_allowed)
				(pads allowed)
				(copperpour not_allowed)
				(footprints allowed)
			)
			(placement
				(enabled no)
				(sheetname "")
			)
			(fill
				(thermal_gap 0.5)
				(thermal_bridge_width 0.5)
				(island_removal_mode 0)
			)
			(polygon
				(pts
					(xy 398.665192 -10.282936) (xy 399.173192 -10.282936) (xy 399.173192 -10.663936) (xy 398.665192 -10.663936)
				)
			)
		)
		(zone
			(layer "F.Cu")
			(hatch none 0.5)
			(connect_pads
				(clearance 0)
			)
			(min_thickness 0.25)
			(keepout
				(tracks not_allowed)
				(vias allowed)
				(pads allowed)
				(copperpour not_allowed)
				(footprints allowed)
			)
			(placement
				(enabled no)
				(sheetname "")
			)
			(fill
				(thermal_gap 0.5)
				(thermal_bridge_width 0.5)
				(island_removal_mode 0)
			)
			(polygon
				(pts
					(xy 398.665192 -10.282936) (xy 399.173192 -10.282936) (xy 399.173192 -10.663936) (xy 398.665192 -10.663936)
				)
			)
		)
	)
	(footprint ""
		(layer "F.Cu")
		(at 19.6342 -97.310956 180)
		(property "Reference" "C1C10"
			(at 0 0 180)
			(layer "F.SilkS")
			(hide yes)
			(effects
				(font
					(size 1.27 1.27)
				)
			)
		)
		(property "Value" ""
			(at 0 0 180)
			(layer "F.Fab")
			(effects
				(font
					(size 1.27 1.27)
				)
			)
		)
		(duplicate_pad_numbers_are_jumpers no)
		(fp_rect
			(start 0.3048 -0.1016)
			(end -0.3048 0.9906)
			(stroke
				(width 0)
				(type default)
			)
			(fill no)
			(layer "F.CrtYd")
		)
		(fp_line
			(start 0.3048 0.9906)
			(end 0.3048 -0.1016)
			(stroke
				(width 0.1)
				(type default)
			)
			(layer "F.Fab")
		)
		(fp_line
			(start 0.3048 -0.1016)
			(end -0.3048 -0.1016)
			(stroke
				(width 0.1)
				(type default)
			)
			(layer "F.Fab")
		)
		(fp_line
			(start -0.3048 0.9906)
			(end 0.3048 0.9906)
			(stroke
				(width 0.1)
				(type default)
			)
			(layer "F.Fab")
		)
		(fp_line
			(start -0.3048 -0.1016)
			(end -0.3048 0.9906)
			(stroke
				(width 0.1)
				(type default)
			)
			(layer "F.Fab")
		)
		(pad "1" smd rect
			(at 0 0 180)
			(size 0.508 0.508)
			(layers "F.Cu" "F.Mask" "F.Paste")
			(net "A_TSENSE_PVCCIN_CPU1")
		)
		(pad "2" smd rect
			(at 0 0.889 180)
			(size 0.508 0.508)
			(layers "F.Cu" "F.Mask" "F.Paste")
			(net "GND")
		)
		(zone
			(layer "F.Cu")
			(hatch none 0.5)
			(connect_pads
				(clearance 0)
			)
			(min_thickness 0.25)
			(keepout
				(tracks not_allowed)
				(vias allowed)
				(pads allowed)
				(copperpour not_allowed)
				(footprints allowed)
			)
			(placement
				(enabled no)
				(sheetname "")
			)
			(fill
				(thermal_gap 0.5)
				(thermal_bridge_width 0.5)
				(island_removal_mode 0)
			)
			(polygon
				(pts
					(xy 19.3802 -97.564956) (xy 19.8882 -97.564956) (xy 19.8882 -97.945956) (xy 19.3802 -97.945956)
				)
			)
		)
		(zone
			(layer "F.Cu")
			(hatch none 0.5)
			(connect_pads
				(clearance 0)
			)
			(min_thickness 0.25)
			(keepout
				(tracks allowed)
				(vias not_allowed)
				(pads allowed)
				(copperpour not_allowed)
				(footprints allowed)
			)
			(placement
				(enabled no)
				(sheetname "")
			)
			(fill
				(thermal_gap 0.5)
				(thermal_bridge_width 0.5)
				(island_removal_mode 0)
			)
			(polygon
				(pts
					(xy 19.3802 -97.564956) (xy 19.8882 -97.564956) (xy 19.8882 -97.945956) (xy 19.3802 -97.945956)
				)
			)
		)
	)
	(footprint ""
		(layer "F.Cu")
		(at 466.54212 -144.907 -90)
		(property "Reference" "R9A15"
			(at 0 0 270)
			(layer "F.SilkS")
			(hide yes)
			(effects
				(font
					(size 1.27 1.27)
				)
			)
		)
		(property "Value" ""
			(at 0 0 270)
			(layer "F.Fab")
			(effects
				(font
					(size 1.27 1.27)
				)
			)
		)
		(duplicate_pad_numbers_are_jumpers no)
		(fp_poly
			(pts
				(xy -0.2794 -0.1016) (xy 0.2794 -0.1016) (xy 0.2794 0.9906) (xy -0.2794 0.9906)
			)
			(stroke
				(width 0)
				(type default)
			)
			(fill no)
			(layer "F.CrtYd")
		)
		(fp_line
			(start -0.2794 0.9906)
			(end 0.2794 0.9906)
			(stroke
				(width 0.1)
				(type default)
			)
			(layer "F.Fab")
		)
		(fp_line
			(start 0.2794 0.9906)
			(end 0.2794 -0.1016)
			(stroke
				(width 0.1)
				(type default)
			)
			(layer "F.Fab")
		)
		(fp_line
			(start -0.2794 -0.1016)
			(end -0.2794 0.9906)
			(stroke
				(width 0.1)
				(type default)
			)
			(layer "F.Fab")
		)
		(fp_line
			(start 0.2794 -0.1016)
			(end -0.2794 -0.1016)
			(stroke
				(width 0.1)
				(type default)
			)
			(layer "F.Fab")
		)
		(pad "1" smd rect
			(at 0 0 270)
			(size 0.508 0.508)
			(layers "F.Cu" "F.Mask" "F.Paste")
			(net "RST_RSMRST_N")
		)
		(pad "2" smd rect
			(at 0 0.889 270)
			(size 0.508 0.508)
			(layers "F.Cu" "F.Mask" "F.Paste")
			(net "XDP_RSMRST_N")
		)
		(zone
			(layer "F.Cu")
			(hatch none 0.5)
			(connect_pads
				(clearance 0)
			)
			(min_thickness 0.25)
			(keepout
				(tracks not_allowed)
				(vias allowed)
				(pads allowed)
				(copperpour not_allowed)
				(footprints allowed)
			)
			(placement
				(enabled no)
				(sheetname "")
			)
			(fill
				(thermal_gap 0.5)
				(thermal_bridge_width 0.5)
				(island_removal_mode 0)
			)
			(polygon
				(pts
					(xy 465.90712 -145.161) (xy 465.90712 -144.653) (xy 466.28812 -144.653) (xy 466.28812 -145.161)
				)
			)
		)
		(zone
			(layer "F.Cu")
			(hatch none 0.5)
			(connect_pads
				(clearance 0)
			)
			(min_thickness 0.25)
			(keepout
				(tracks allowed)
				(vias not_allowed)
				(pads allowed)
				(copperpour not_allowed)
				(footprints allowed)
			)
			(placement
				(enabled no)
				(sheetname "")
			)
			(fill
				(thermal_gap 0.5)
				(thermal_bridge_width 0.5)
				(island_removal_mode 0)
			)
			(polygon
				(pts
					(xy 466.28812 -145.161) (xy 466.28812 -144.653) (xy 465.90712 -144.653) (xy 465.90712 -145.161)
				)
			)
		)
	)
)
